(kicad_pcb
	(version 20241229)
	(generator "pcbnew")
	(generator_version "9.0")
	(general
		(thickness 1.294)
		(legacy_teardrops no)
	)
	(paper "A3")
	(title_block
		(title "Kintex 410T devboard")
		(date "2024-04-03")
		(rev "1.1.2")
		(comment 9 "footprints 807-811 of 975")
	)
	(layers
		(0 "F.Cu" mixed)
		(4 "In1.Cu" power)
		(6 "In2.Cu" power)
		(8 "In3.Cu" mixed)
		(10 "In4.Cu" power)
		(12 "In5.Cu" mixed)
		(14 "In6.Cu" power)
		(16 "In7.Cu" mixed)
		(18 "In8.Cu" power)
		(2 "B.Cu" mixed)
		(9 "F.Adhes" user "F.Adhesive")
		(11 "B.Adhes" user "B.Adhesive")
		(13 "F.Paste" user)
		(15 "B.Paste" user)
		(5 "F.SilkS" user "F.Silkscreen")
		(7 "B.SilkS" user "B.Silkscreen")
		(1 "F.Mask" user)
		(3 "B.Mask" user)
		(17 "Dwgs.User" user "User.Drawings")
		(19 "Cmts.User" user "User.Comments")
		(21 "Eco1.User" user "User.Eco1")
		(23 "Eco2.User" user "User.Eco2")
		(25 "Edge.Cuts" user)
		(27 "Margin" user)
		(31 "F.CrtYd" user "F.Courtyard")
		(29 "B.CrtYd" user "B.Courtyard")
		(35 "F.Fab" user)
		(33 "B.Fab" user)
	)
	(footprint "antmicro-footprints:C_0402_1005Metric"
		(layer "B.Cu")
		(at 198.325 126.825 180)
		(descr "Capacitor SMD 0402")
		(tags "capacitor SMD 0402")
		(property "Reference" "C131"
			(at -26.3 29.375 0)
			(layer "B.SilkS")
			(effects
				(font
					(size 0.7 0.7)
					(thickness 0.15)
				)
				(justify left bottom mirror)
			)
		)
		(property "Value" "C_100n_0402"
			(at 0 -1.169 0)
			(layer "B.Fab")
			(effects
				(font
					(size 0.7 0.7)
					(thickness 0.15)
				)
				(justify left bottom mirror)
			)
		)
		(property "Description" "SMD Multilayer Ceramic Capacitor, 0.1 µF, 50 V, 0402 [1005 Metric], ± 10%, X5R, GRM Series"
			(at 0 0 180)
			(layer "F.Fab")
			(hide yes)
			(effects
				(font
					(size 1.27 1.27)
					(thickness 0.15)
				)
			)
		)
		(property "Author" "Antmicro"
			(at 396.65 253.65 0)
			(layer "B.Fab")
			(hide yes)
			(effects
				(font
					(size 1 1)
					(thickness 0.15)
				)
				(justify mirror)
			)
		)
		(property "Dielectric" "X5R"
			(at 396.65 253.65 0)
			(layer "B.Fab")
			(hide yes)
			(effects
				(font
					(size 1 1)
					(thickness 0.15)
				)
				(justify mirror)
			)
		)
		(property "License" "Apache-2.0"
			(at 396.65 253.65 0)
			(layer "B.Fab")
			(hide yes)
			(effects
				(font
					(size 1 1)
					(thickness 0.15)
				)
				(justify mirror)
			)
		)
		(property "MPN" "GRM155R61H104KE14D"
			(at 396.65 253.65 0)
			(layer "B.Fab")
			(hide yes)
			(effects
				(font
					(size 1 1)
					(thickness 0.15)
				)
				(justify mirror)
			)
		)
		(property "Manufacturer" "Murata"
			(at 396.65 253.65 0)
			(layer "B.Fab")
			(hide yes)
			(effects
				(font
					(size 1 1)
					(thickness 0.15)
				)
				(justify mirror)
			)
		)
		(property "Val" "100n"
			(at 396.65 253.65 0)
			(layer "B.Fab")
			(hide yes)
			(effects
				(font
					(size 1 1)
					(thickness 0.15)
				)
				(justify mirror)
			)
		)
		(property "Voltage" "50V"
			(at 396.65 253.65 0)
			(layer "B.Fab")
			(hide yes)
			(effects
				(font
					(size 1 1)
					(thickness 0.15)
				)
				(justify mirror)
			)
		)
		(sheetname "FPGA supply")
		(sheetfile "fpga-supply.kicad_sch")
		(attr smd)
		(fp_rect
			(start -0.925 0.47)
			(end 0.925 -0.47)
			(stroke
				(width 0.05)
				(type default)
			)
			(fill no)
			(layer "B.CrtYd")
		)
		(fp_line
			(start 0.504 0.25)
			(end 0.504 -0.248)
			(stroke
				(width 0.15)
				(type solid)
			)
			(layer "B.Fab")
		)
		(fp_line
			(start 0.504 -0.248)
			(end -0.494 -0.248)
			(stroke
				(width 0.15)
				(type solid)
			)
			(layer "B.Fab")
		)
		(fp_line
			(start -0.494 0.25)
			(end 0.504 0.25)
			(stroke
				(width 0.15)
				(type solid)
			)
			(layer "B.Fab")
		)
		(fp_line
			(start -0.494 -0.248)
			(end -0.494 0.25)
			(stroke
				(width 0.15)
				(type solid)
			)
			(layer "B.Fab")
		)
		(pad "1" smd roundrect
			(at -0.48 0 180)
			(size 0.59 0.64)
			(layers "B.Cu" "B.Mask" "B.Paste")
			(roundrect_rratio 0.25)
			(net 1 "GND")
			(pintype "passive")
		)
		(pad "2" smd roundrect
			(at 0.48 0 180)
			(size 0.59 0.64)
			(layers "B.Cu" "B.Mask" "B.Paste")
			(roundrect_rratio 0.25)
			(net 650 "+1V0")
			(pintype "passive")
		)
	)
	(footprint "antmicro-footprints:C_0402_1005Metric"
		(layer "B.Cu")
		(at 187.25 137.25 -90)
		(descr "Capacitor SMD 0402")
		(tags "capacitor SMD 0402")
		(property "Reference" "C62"
			(at -1.1 0.5 90)
			(layer "B.SilkS")
			(effects
				(font
					(size 0.7 0.7)
					(thickness 0.15)
				)
				(justify left bottom mirror)
			)
		)
		(property "Value" "C_100n_0402"
			(at 0 -1.169 90)
			(layer "B.Fab")
			(effects
				(font
					(size 0.7 0.7)
					(thickness 0.15)
				)
				(justify left bottom mirror)
			)
		)
		(property "Description" "SMD Multilayer Ceramic Capacitor, 0.1 µF, 50 V, 0402 [1005 Metric], ± 10%, X5R, GRM Series"
			(at 0 0 270)
			(layer "F.Fab")
			(hide yes)
			(effects
				(font
					(size 1.27 1.27)
					(thickness 0.15)
				)
			)
		)
		(property "Author" "Antmicro"
			(at 50 324.5 0)
			(layer "B.Fab")
			(hide yes)
			(effects
				(font
					(size 1 1)
					(thickness 0.15)
				)
				(justify mirror)
			)
		)
		(property "Dielectric" "X5R"
			(at 50 324.5 0)
			(layer "B.Fab")
			(hide yes)
			(effects
				(font
					(size 1 1)
					(thickness 0.15)
				)
				(justify mirror)
			)
		)
		(property "License" "Apache-2.0"
			(at 50 324.5 0)
			(layer "B.Fab")
			(hide yes)
			(effects
				(font
					(size 1 1)
					(thickness 0.15)
				)
				(justify mirror)
			)
		)
		(property "MPN" "GRM155R61H104KE14D"
			(at 50 324.5 0)
			(layer "B.Fab")
			(hide yes)
			(effects
				(font
					(size 1 1)
					(thickness 0.15)
				)
				(justify mirror)
			)
		)
		(property "Manufacturer" "Murata"
			(at 50 324.5 0)
			(layer "B.Fab")
			(hide yes)
			(effects
				(font
					(size 1 1)
					(thickness 0.15)
				)
				(justify mirror)
			)
		)
		(property "Val" "100n"
			(at 50 324.5 0)
			(layer "B.Fab")
			(hide yes)
			(effects
				(font
					(size 1 1)
					(thickness 0.15)
				)
				(justify mirror)
			)
		)
		(property "Voltage" "50V"
			(at 50 324.5 0)
			(layer "B.Fab")
			(hide yes)
			(effects
				(font
					(size 1 1)
					(thickness 0.15)
				)
				(justify mirror)
			)
		)
		(sheetname "FPGA Bank 33 & 34")
		(sheetfile "fpga-bank-33-34.kicad_sch")
		(attr smd)
		(fp_rect
			(start -0.925 0.47)
			(end 0.925 -0.47)
			(stroke
				(width 0.05)
				(type default)
			)
			(fill no)
			(layer "B.CrtYd")
		)
		(fp_line
			(start -0.494 0.25)
			(end 0.504 0.25)
			(stroke
				(width 0.15)
				(type solid)
			)
			(layer "B.Fab")
		)
		(fp_line
			(start 0.504 0.25)
			(end 0.504 -0.248)
			(stroke
				(width 0.15)
				(type solid)
			)
			(layer "B.Fab")
		)
		(fp_line
			(start -0.494 -0.248)
			(end -0.494 0.25)
			(stroke
				(width 0.15)
				(type solid)
			)
			(layer "B.Fab")
		)
		(fp_line
			(start 0.504 -0.248)
			(end -0.494 -0.248)
			(stroke
				(width 0.15)
				(type solid)
			)
			(layer "B.Fab")
		)
		(pad "1" smd roundrect
			(at -0.48 0 270)
			(size 0.59 0.64)
			(layers "B.Cu" "B.Mask" "B.Paste")
			(roundrect_rratio 0.25)
			(net 1 "GND")
			(pintype "passive")
		)
		(pad "2" smd roundrect
			(at 0.48 0 270)
			(size 0.59 0.64)
			(layers "B.Cu" "B.Mask" "B.Paste")
			(roundrect_rratio 0.25)
			(net 25 "+1V35")
			(pintype "passive")
		)
	)
	(footprint "antmicro-footprints:C_0402_1005Metric"
		(layer "B.Cu")
		(at 191.75 126.275)
		(descr "Capacitor SMD 0402")
		(tags "capacitor SMD 0402")
		(property "Reference" "C103"
			(at 22.975 -29.3 180)
			(layer "B.SilkS")
			(effects
				(font
					(size 0.7 0.7)
					(thickness 0.15)
				)
				(justify left bottom mirror)
			)
		)
		(property "Value" "C_100n_0402"
			(at 0 -1.169 180)
			(layer "B.Fab")
			(effects
				(font
					(size 0.7 0.7)
					(thickness 0.15)
				)
				(justify left bottom mirror)
			)
		)
		(property "Description" "SMD Multilayer Ceramic Capacitor, 0.1 µF, 50 V, 0402 [1005 Metric], ± 10%, X5R, GRM Series"
			(at 0 0 0)
			(layer "F.Fab")
			(hide yes)
			(effects
				(font
					(size 1.27 1.27)
					(thickness 0.15)
				)
			)
		)
		(property "Author" "Antmicro"
			(at 0 0 0)
			(layer "B.Fab")
			(hide yes)
			(effects
				(font
					(size 1 1)
					(thickness 0.15)
				)
				(justify mirror)
			)
		)
		(property "Dielectric" "X5R"
			(at 0 0 0)
			(layer "B.Fab")
			(hide yes)
			(effects
				(font
					(size 1 1)
					(thickness 0.15)
				)
				(justify mirror)
			)
		)
		(property "License" "Apache-2.0"
			(at 0 0 0)
			(layer "B.Fab")
			(hide yes)
			(effects
				(font
					(size 1 1)
					(thickness 0.15)
				)
				(justify mirror)
			)
		)
		(property "MPN" "GRM155R61H104KE14D"
			(at 0 0 0)
			(layer "B.Fab")
			(hide yes)
			(effects
				(font
					(size 1 1)
					(thickness 0.15)
				)
				(justify mirror)
			)
		)
		(property "Manufacturer" "Murata"
			(at 0 0 0)
			(layer "B.Fab")
			(hide yes)
			(effects
				(font
					(size 1 1)
					(thickness 0.15)
				)
				(justify mirror)
			)
		)
		(property "Val" "100n"
			(at 0 0 0)
			(layer "B.Fab")
			(hide yes)
			(effects
				(font
					(size 1 1)
					(thickness 0.15)
				)
				(justify mirror)
			)
		)
		(property "Voltage" "50V"
			(at 0 0 0)
			(layer "B.Fab")
			(hide yes)
			(effects
				(font
					(size 1 1)
					(thickness 0.15)
				)
				(justify mirror)
			)
		)
		(sheetname "FPGA supply")
		(sheetfile "fpga-supply.kicad_sch")
		(attr smd)
		(fp_rect
			(start -0.925 0.47)
			(end 0.925 -0.47)
			(stroke
				(width 0.05)
				(type default)
			)
			(fill no)
			(layer "B.CrtYd")
		)
		(fp_line
			(start -0.494 -0.248)
			(end -0.494 0.25)
			(stroke
				(width 0.15)
				(type solid)
			)
			(layer "B.Fab")
		)
		(fp_line
			(start -0.494 0.25)
			(end 0.504 0.25)
			(stroke
				(width 0.15)
				(type solid)
			)
			(layer "B.Fab")
		)
		(fp_line
			(start 0.504 -0.248)
			(end -0.494 -0.248)
			(stroke
				(width 0.15)
				(type solid)
			)
			(layer "B.Fab")
		)
		(fp_line
			(start 0.504 0.25)
			(end 0.504 -0.248)
			(stroke
				(width 0.15)
				(type solid)
			)
			(layer "B.Fab")
		)
		(pad "1" smd roundrect
			(at -0.48 0)
			(size 0.59 0.64)
			(layers "B.Cu" "B.Mask" "B.Paste")
			(roundrect_rratio 0.25)
			(net 6 "+1V0_MGTAVCC")
			(pintype "passive")
		)
		(pad "2" smd roundrect
			(at 0.48 0)
			(size 0.59 0.64)
			(layers "B.Cu" "B.Mask" "B.Paste")
			(roundrect_rratio 0.25)
			(net 1 "GND")
			(pintype "passive")
		)
	)
	(footprint "antmicro-footprints:R_0603_1608Metric"
		(layer "B.Cu")
		(at 262.401 170.3 180)
		(descr "Resistor SMD 0603")
		(tags "resistor SMD 0603")
		(property "Reference" "R251"
			(at 1.051 -0.375 0)
			(layer "B.SilkS")
			(effects
				(font
					(size 0.7 0.7)
					(thickness 0.15)
				)
				(justify left bottom mirror)
			)
		)
		(property "Value" "R_220R_0603"
			(at 0 -1.6 0)
			(layer "B.Fab")
			(effects
				(font
					(size 0.7 0.7)
					(thickness 0.15)
				)
				(justify left bottom mirror)
			)
		)
		(property "Description" "SMD Chip Resistor, 220 ohm, ± 1%, 100 mW, 0603 [1608 Metric], Thick Film, General Purpose"
			(at 0 0 180)
			(layer "F.Fab")
			(hide yes)
			(effects
				(font
					(size 1.27 1.27)
					(thickness 0.15)
				)
			)
		)
		(property "Author" "Antmicro"
			(at 524.802 340.6 0)
			(layer "B.Fab")
			(hide yes)
			(effects
				(font
					(size 1 1)
					(thickness 0.15)
				)
				(justify mirror)
			)
		)
		(property "License" "Apache-2.0"
			(at 524.802 340.6 0)
			(layer "B.Fab")
			(hide yes)
			(effects
				(font
					(size 1 1)
					(thickness 0.15)
				)
				(justify mirror)
			)
		)
		(property "MPN" "CR0603-FX-2200ELF"
			(at 524.802 340.6 0)
			(layer "B.Fab")
			(hide yes)
			(effects
				(font
					(size 1 1)
					(thickness 0.15)
				)
				(justify mirror)
			)
		)
		(property "Manufacturer" "Bourns"
			(at 524.802 340.6 0)
			(layer "B.Fab")
			(hide yes)
			(effects
				(font
					(size 1 1)
					(thickness 0.15)
				)
				(justify mirror)
			)
		)
		(property "Tolerance" "1%"
			(at 524.802 340.6 0)
			(layer "B.Fab")
			(hide yes)
			(effects
				(font
					(size 1 1)
					(thickness 0.15)
				)
				(justify mirror)
			)
		)
		(property "Val" "220R"
			(at 524.802 340.6 0)
			(layer "B.Fab")
			(hide yes)
			(effects
				(font
					(size 1 1)
					(thickness 0.15)
				)
				(justify mirror)
			)
		)
		(sheetname "HDMI + Ethernet")
		(sheetfile "hdmi-ethernet.kicad_sch")
		(attr smd)
		(fp_line
			(start -0.15 0.4)
			(end 0.15 0.4)
			(stroke
				(width 0.15)
				(type solid)
			)
			(layer "B.SilkS")
		)
		(fp_line
			(start -0.15 -0.4)
			(end 0.15 -0.4)
			(stroke
				(width 0.15)
				(type solid)
			)
			(layer "B.SilkS")
		)
		(fp_rect
			(start -1.25 0.65)
			(end 1.25 -0.65)
			(stroke
				(width 0.05)
				(type solid)
			)
			(fill no)
			(layer "B.CrtYd")
		)
		(fp_rect
			(start -0.8 0.4)
			(end 0.8 -0.4)
			(stroke
				(width 0.15)
				(type solid)
			)
			(fill no)
			(layer "B.Fab")
		)
		(pad "1" smd roundrect
			(at -0.7 0 180)
			(size 0.8 1)
			(layers "B.Cu" "B.Mask" "B.Paste")
			(roundrect_rratio 0.2)
			(net 845 "/HDMI + Ethernet/ETH_LED_LINK+")
			(pintype "passive")
		)
		(pad "2" smd roundrect
			(at 0.7 0 180)
			(size 0.8 1)
			(layers "B.Cu" "B.Mask" "B.Paste")
			(roundrect_rratio 0.2)
			(net 24 "+3V3")
			(pintype "passive")
		)
	)
	(footprint "antmicro-footprints:R_Array_4x0201_Panasonic_EXB18V"
		(layer "B.Cu")
		(at 251.251 137.7 90)
		(property "Reference" "R61"
			(at -1.1 -0.701 270)
			(layer "B.SilkS")
			(effects
				(font
					(size 0.7 0.7)
					(thickness 0.15)
				)
				(justify right bottom mirror)
			)
		)
		(property "Value" "R_4x33R_0201_array"
			(at -1.1 -1.8 270)
			(layer "B.Fab")
			(effects
				(font
					(size 0.7 0.7)
					(thickness 0.15)
				)
				(justify left bottom mirror)
			)
		)
		(property "Description" "Fixed Network Resistor, 33 ohm, Isolated, 4 Resistors, 0502 [1406 Metric], Flat, ± 5%"
			(at 0 0 90)
			(layer "F.Fab")
			(hide yes)
			(effects
				(font
					(size 1.27 1.27)
					(thickness 0.15)
				)
			)
		)
		(property "Author" "Antmicro"
			(at 388.951 -113.551 0)
			(layer "B.Fab")
			(hide yes)
			(effects
				(font
					(size 1 1)
					(thickness 0.15)
				)
				(justify mirror)
			)
		)
		(property "License" "Apache-2.0"
			(at 388.951 -113.551 0)
			(layer "B.Fab")
			(hide yes)
			(effects
				(font
					(size 1 1)
					(thickness 0.15)
				)
				(justify mirror)
			)
		)
		(property "MPN" "EXB-18V330JX"
			(at 388.951 -113.551 0)
			(layer "B.Fab")
			(hide yes)
			(effects
				(font
					(size 1 1)
					(thickness 0.15)
				)
				(justify mirror)
			)
		)
		(property "Manufacturer" "Panasonic"
			(at 388.951 -113.551 0)
			(layer "B.Fab")
			(hide yes)
			(effects
				(font
					(size 1 1)
					(thickness 0.15)
				)
				(justify mirror)
			)
		)
		(property "Val" "R_4x33R_0201"
			(at 388.951 -113.551 0)
			(layer "B.Fab")
			(hide yes)
			(effects
				(font
					(size 1 1)
					(thickness 0.15)
				)
				(justify mirror)
			)
		)
		(sheetname "SPI Flash + SD Card")
		(sheetfile "spi-flash.kicad_sch")
		(attr smd)
		(fp_line
			(start 0.8 0.45)
			(end 0.8 -0.45)
			(stroke
				(width 0.12)
				(type solid)
			)
			(layer "B.SilkS")
		)
		(fp_line
			(start -0.8 0.45)
			(end -0.8 -0.45)
			(stroke
				(width 0.12)
				(type solid)
			)
			(layer "B.SilkS")
		)
		(fp_rect
			(start -0.898 0.66)
			(end 0.898 -0.65)
			(stroke
				(width 0.05)
				(type solid)
			)
			(fill no)
			(layer "B.CrtYd")
		)
		(pad "1" smd roundrect
			(at -0.6 -0.298 90)
			(size 0.2 0.4)
			(layers "B.Cu" "B.Mask" "B.Paste")
			(roundrect_rratio 0.25)
			(net 390 "/FPGA Bank 33 & 34/SD_CARD.DAT2")
			(pinfunction "R1.1")
			(pintype "passive")
		)
		(pad "2" smd roundrect
			(at -0.202 -0.298 90)
			(size 0.2 0.4)
			(layers "B.Cu" "B.Mask" "B.Paste")
			(roundrect_rratio 0.25)
			(net 391 "/FPGA Bank 33 & 34/SD_CARD.DAT3")
			(pinfunction "R2.1")
			(pintype "passive")
		)
		(pad "3" smd roundrect
			(at 0.2 -0.298 90)
			(size 0.2 0.4)
			(layers "B.Cu" "B.Mask" "B.Paste")
			(roundrect_rratio 0.25)
			(net 393 "/FPGA Bank 33 & 34/SD_CARD.CMD")
			(pinfunction "R3.1")
			(pintype "passive")
		)
		(pad "4" smd roundrect
			(at 0.598 -0.298 90)
			(size 0.2 0.4)
			(layers "B.Cu" "B.Mask" "B.Paste")
			(roundrect_rratio 0.25)
			(net 363 "unconnected-(R61-R4.1-Pad4)")
			(pinfunction "R4.1")
			(pintype "passive+no_connect")
		)
		(pad "5" smd roundrect
			(at 0.598 0.3 90)
			(size 0.2 0.4)
			(layers "B.Cu" "B.Mask" "B.Paste")
			(roundrect_rratio 0.25)
			(net 364 "unconnected-(R61-R4.2-Pad5)")
			(pinfunction "R4.2")
			(pintype "passive+no_connect")
		)
		(pad "6" smd roundrect
			(at 0.2 0.3 90)
			(size 0.2 0.4)
			(layers "B.Cu" "B.Mask" "B.Paste")
			(roundrect_rratio 0.25)
			(net 329 "Net-(J23-CMD)")
			(pinfunction "R3.2")
			(pintype "passive")
		)
		(pad "7" smd roundrect
			(at -0.202 0.3 90)
			(size 0.2 0.4)
			(layers "B.Cu" "B.Mask" "B.Paste")
			(roundrect_rratio 0.25)
			(net 328 "Net-(J23-DAT3{slash}CD)")
			(pinfunction "R2.2")
			(pintype "passive")
		)
		(pad "8" smd roundrect
			(at -0.6 0.3 90)
			(size 0.2 0.4)
			(layers "B.Cu" "B.Mask" "B.Paste")
			(roundrect_rratio 0.25)
			(net 327 "Net-(J23-DAT2)")
			(pinfunction "R1.2")
			(pintype "passive")
		)
	)
)
